(kicad_pcb
	(version 20221018)
	(generator pcbnew)
	(general
    (thickness 1.518)
  )
	(paper "A4")
	(title_block
    (title "Kria K26 Devboard")
    (date "2024-03-26")
    (rev "1.2.5")
    (comment 1 "www.antmicro.com")
    (comment 2 "Antmicro Ltd.")
		(comment 9 "footprints 315-322 of 660")
	)
	(layers
    (0 "F.Cu" mixed)
    (1 "In1.Cu" power)
    (2 "In2.Cu" mixed)
    (3 "In3.Cu" power)
    (4 "In4.Cu" mixed)
    (5 "In5.Cu" power)
    (6 "In6.Cu" mixed)
    (31 "B.Cu" power)
    (32 "B.Adhes" user "B.Adhesive")
    (33 "F.Adhes" user "F.Adhesive")
    (34 "B.Paste" user)
    (35 "F.Paste" user)
    (36 "B.SilkS" user "B.Silkscreen")
    (37 "F.SilkS" user "F.Silkscreen")
    (38 "B.Mask" user)
    (39 "F.Mask" user)
    (40 "Dwgs.User" user "User.Drawings")
    (41 "Cmts.User" user "User.Comments")
    (42 "Eco1.User" user "User.Eco1")
    (43 "Eco2.User" user "User.Eco2")
    (44 "Edge.Cuts" user)
    (45 "Margin" user)
    (46 "B.CrtYd" user "B.Courtyard")
    (47 "F.CrtYd" user "F.Courtyard")
    (48 "B.Fab" user)
    (49 "F.Fab" user)
  )
	(footprint "kria-k26-devboard-footprints:TP_SMD_0.75mm" (layer "F.Cu")
    (at 185.45 62.7)
    (property "Author" "Antmicro")
    (property "License" "Apache-2.0")
    (property "MPN" "")
    (property "Manufacturer" "")
    (property "Sheetfile" "dc-input.kicad_sch")
    (property "Sheetname" "DC Input")
    (property "ki_description" "Test Point 0.75mm")
    (attr exclude_from_pos_files)
    (fp_text reference "TP46" (at 0.33 -0.25 90) (layer "F.SilkS")
        (effects (font (size 0.7 0.7) (thickness 0.15)) (justify left bottom))
    )
    (fp_text value "TP_0.75mm_SMD" (at 0 1.2) (layer "F.Fab") hide
        (effects (font (size 0.7 0.7) (thickness 0.15)) (justify left bottom))
    )
    (fp_text user "Author: Antmicro" (at -0.4 3.901) (layer "F.Fab") hide
        (effects (font (size 0.7 0.7) (thickness 0.15)) (justify left bottom))
    )
    (fp_text user "License: Apache-2.0" (at -0.4 5.101) (layer "F.Fab") hide
        (effects (font (size 0.7 0.7) (thickness 0.15)) (justify left bottom))
    )
    (fp_text user "${REFERENCE}" (at -0.4 2.7) (layer "F.Fab") hide
        (effects (font (size 0.7 0.7) (thickness 0.15)) (justify left bottom))
    )
    (pad "1" smd circle (at 0 0) (size 0.75 0.75) (layers "F.Cu" "F.Mask")
      (net 22 "/Power Supply/DC Input/DC_IN") (pinfunction "1") (pintype "passive"))
  )
	(footprint "kria-k26-devboard-footprints:C_0603_1608Metric" (layer "F.Cu")
    (at 172 137.65 180)
    (descr "Capacitor SMD 0603")
    (tags "capacitor 0603")
    (property "Author" "Antmicro")
    (property "Dielectric" "")
    (property "License" "Apache-2.0")
    (property "MPN" "C1608X5R1E106M080AC")
    (property "Manufacturer" "TDK")
    (property "Sheetfile" "dc-dc-conventers.kicad_sch")
    (property "Sheetname" "DC/DC conventers")
    (property "Val" "10u/25V")
    (property "Voltage" "")
    (property "ki_description" " ")
    (attr smd)
    (fp_text reference "C201" (at 1.39 -1.57 180) (layer "F.SilkS")
        (effects (font (size 0.7 0.7) (thickness 0.15)) (justify left bottom))
    )
    (fp_text value "C_10u_25V_0603" (at 0 1.6 180) (layer "F.Fab") hide
        (effects (font (size 0.7 0.7) (thickness 0.15)) (justify left bottom))
    )
    (fp_text user "Author: Antmicro" (at -1.682 4.894 180) (layer "F.Fab") hide
        (effects (font (size 0.7 0.7) (thickness 0.15)) (justify left bottom))
    )
    (fp_text user "License: Apache-2.0" (at -1.682 5.895 180) (layer "F.Fab") hide
        (effects (font (size 0.7 0.7) (thickness 0.15)) (justify left bottom))
    )
    (fp_text user "${REFERENCE}" (at -1.682 3.895 180) (layer "F.Fab") hide
        (effects (font (size 0.7 0.7) (thickness 0.15)) (justify left bottom))
    )
    (fp_line (start -0.3 -0.3) (end 0.3 -0.3)
      (stroke (width 0.15) (type solid)) (layer "F.SilkS"))
    (fp_line (start -0.3 0.3) (end 0.3 0.3)
      (stroke (width 0.15) (type solid)) (layer "F.SilkS"))
    (fp_rect (start -1.24 -0.7) (end 1.24 0.7)
      (stroke (width 0.05) (type solid)) (fill none) (layer "F.CrtYd"))
    (fp_rect (start -0.8 -0.4) (end 0.8 0.4)
      (stroke (width 0.15) (type solid)) (fill none) (layer "F.Fab"))
    (pad "1" smd roundrect (at -0.7 0 180) (size 0.6 0.8) (layers "F.Cu" "F.Paste" "F.Mask") (roundrect_rratio 0.2)
      (net 14 "/Power Supply/DC/DC conventers/DC_MAIN_BUS") (pintype "passive"))
    (pad "2" smd roundrect (at 0.7 0 180) (size 0.6 0.8) (layers "F.Cu" "F.Paste" "F.Mask") (roundrect_rratio 0.2)
      (net 1 "GND") (pintype "passive"))
  )
	(footprint "kria-k26-devboard-footprints:FB_0402_1005Metric" (layer "F.Cu")
    (at 151.14 123.52 180)
    (descr "Ferrite Bead SMD 0402")
    (tags "ferrite bead SMD 0402")
    (property "Author" "Antmicro")
    (property "License" "Apache-2.0")
    (property "MPN" "BLM15PD121SN1D")
    (property "Manufacturer" "Murata")
    (property "Sheetfile" "debug.kicad_sch")
    (property "Sheetname" "Debug and JTAG")
    (attr smd)
    (fp_text reference "FB4" (at 3.14 -0.37 180) (layer "F.SilkS")
        (effects (font (size 0.7 0.7) (thickness 0.15)) (justify left bottom))
    )
    (fp_text value "FB_120Z_1.3A_0402" (at 0 1.4 180) (layer "F.Fab") hide
        (effects (font (size 0.7 0.7) (thickness 0.15)) (justify left bottom))
    )
    (fp_text user "License: Apache-2.0" (at -0.95 5.169 180) (layer "F.Fab") hide
        (effects (font (size 0.7 0.7) (thickness 0.15)) (justify left bottom))
    )
    (fp_text user "Author: Antmicro" (at -0.95 4.169 180) (layer "F.Fab") hide
        (effects (font (size 0.7 0.7) (thickness 0.15)) (justify left bottom))
    )
    (fp_text user "${REFERENCE}" (at -0.95 3.168 180) (layer "F.Fab") hide
        (effects (font (size 0.7 0.7) (thickness 0.15)) (justify left bottom))
    )
    (fp_rect (start -0.95 -0.48) (end 0.95 0.48)
      (stroke (width 0.05) (type solid)) (fill none) (layer "F.CrtYd"))
    (fp_rect (start -0.5 -0.25) (end 0.5 0.25)
      (stroke (width 0.15) (type solid)) (fill none) (layer "F.Fab"))
    (pad "1" smd roundrect (at -0.485 0 180) (size 0.59 0.64) (layers "F.Cu" "F.Paste" "F.Mask") (roundrect_rratio 0.25)
      (net 138 "/Debug and JTAG/USB_3V3") (pintype "passive"))
    (pad "2" smd roundrect (at 0.485 0 180) (size 0.59 0.64) (layers "F.Cu" "F.Paste" "F.Mask") (roundrect_rratio 0.25)
      (net 134 "/Debug and JTAG/VREGIN") (pintype "passive"))
  )
	(footprint "kria-k26-devboard-footprints:TP_SMD_0.75mm" (layer "F.Cu")
    (at 190.8 123.65)
    (property "Author" "Antmicro")
    (property "License" "Apache-2.0")
    (property "MPN" "")
    (property "Manufacturer" "")
    (property "Sheetfile" "supply-oring.kicad_sch")
    (property "Sheetname" "Supply ORing")
    (property "ki_description" "Test Point 0.75mm")
    (attr exclude_from_pos_files)
    (fp_text reference "TP43" (at 0.4 3 90) (layer "F.SilkS")
        (effects (font (size 0.7 0.7) (thickness 0.15)) (justify left bottom))
    )
    (fp_text value "TP_0.75mm_SMD" (at 0 1.2) (layer "F.Fab") hide
        (effects (font (size 0.7 0.7) (thickness 0.15)) (justify left bottom))
    )
    (fp_text user "Author: Antmicro" (at -0.4 3.901) (layer "F.Fab") hide
        (effects (font (size 0.7 0.7) (thickness 0.15)) (justify left bottom))
    )
    (fp_text user "License: Apache-2.0" (at -0.4 5.101) (layer "F.Fab") hide
        (effects (font (size 0.7 0.7) (thickness 0.15)) (justify left bottom))
    )
    (fp_text user "${REFERENCE}" (at -0.4 2.7) (layer "F.Fab") hide
        (effects (font (size 0.7 0.7) (thickness 0.15)) (justify left bottom))
    )
    (pad "1" smd circle (at 0 0) (size 0.75 0.75) (layers "F.Cu" "F.Mask")
      (net 14 "/Power Supply/DC/DC conventers/DC_MAIN_BUS") (pinfunction "1") (pintype "passive"))
  )
	(footprint "kria-k26-devboard-footprints:TP_SMD_0.75mm" (layer "F.Cu")
    (at 138.6 96.4)
    (property "Author" "Antmicro")
    (property "License" "Apache-2.0")
    (property "MPN" "")
    (property "Manufacturer" "")
    (property "Sheetfile" "dc-dc-conventers.kicad_sch")
    (property "Sheetname" "DC/DC conventers")
    (property "ki_description" "Test Point 0.75mm")
    (attr exclude_from_pos_files)
    (fp_text reference "TP40" (at -1.32 1.23) (layer "F.SilkS")
        (effects (font (size 0.7 0.7) (thickness 0.15)) (justify left bottom))
    )
    (fp_text value "TP_0.75mm_SMD" (at 0 1.2) (layer "F.Fab") hide
        (effects (font (size 0.7 0.7) (thickness 0.15)) (justify left bottom))
    )
    (fp_text user "License: Apache-2.0" (at -0.4 5.101) (layer "F.Fab") hide
        (effects (font (size 0.7 0.7) (thickness 0.15)) (justify left bottom))
    )
    (fp_text user "Author: Antmicro" (at -0.4 3.901) (layer "F.Fab") hide
        (effects (font (size 0.7 0.7) (thickness 0.15)) (justify left bottom))
    )
    (fp_text user "${REFERENCE}" (at -0.4 2.7) (layer "F.Fab") hide
        (effects (font (size 0.7 0.7) (thickness 0.15)) (justify left bottom))
    )
    (pad "1" smd circle (at 0 0) (size 0.75 0.75) (layers "F.Cu" "F.Mask")
      (net 769 "/Power Supply/DC/DC conventers/PS_1V0_OUT") (pinfunction "1") (pintype "passive"))
  )
	(footprint "kria-k26-devboard-footprints:UQFN-13_2x3mm_P0.5mm" (layer "F.Cu")
    (at 173.15 125.1 90)
    (property "Author" "Antmicro")
    (property "License" "Apache-2.0")
    (property "MPN" "RT6236AHGQUF")
    (property "Manufacturer" "Richtek")
    (property "Sheetfile" "dc-dc-conventers.kicad_sch")
    (property "Sheetname" "DC/DC conventers")
    (property "ki_description" "DC-DC Switching Buck Step Down Regulator, Adjustable, 4.5V-18Vin, 700mV-8V/6A out, 650kHz, UQFN-13")
    (property "ki_keywords" "SMT, PMIC, IC, SWITCHING, VOLTAGE, REGULATOR, DC-DC")
    (attr smd)
    (fp_text reference "U48" (at 1.51 -0.2 180) (layer "F.SilkS")
        (effects (font (size 0.7 0.7) (thickness 0.15)) (justify left bottom))
    )
    (fp_text value "RT6236AHGQUF" (at 0.812 3.293 90) (layer "F.Fab") hide
        (effects (font (size 0.7 0.7) (thickness 0.15)) (justify left bottom))
    )
    (fp_text user "License: Apache-2.0" (at -1.537 7.693 90) (layer "F.Fab") hide
        (effects (font (size 0.7 0.7) (thickness 0.15)) (justify left bottom))
    )
    (fp_text user "${REFERENCE}" (at -1.537 5.294 90) (layer "F.Fab") hide
        (effects (font (size 0.7 0.7) (thickness 0.15)) (justify left bottom))
    )
    (fp_text user "Author: Antmicro" (at -1.537 6.493 90) (layer "F.Fab") hide
        (effects (font (size 0.7 0.7) (thickness 0.15)) (justify left bottom))
    )
    (fp_circle (center -1.25 -1.65) (end -1.2 -1.65)
      (stroke (width 0.15) (type solid)) (fill solid) (layer "F.SilkS"))
    (fp_rect (start -1.65 -2.15) (end 1.65 2.15)
      (stroke (width 0.05) (type solid)) (fill none) (layer "F.CrtYd"))
    (fp_line (start -0.9 -0.85) (end -0.45 -1.3)
      (stroke (width 0.15) (type solid)) (layer "F.Fab"))
    (fp_line (start -0.9 1.3) (end -0.9 -0.85)
      (stroke (width 0.15) (type solid)) (layer "F.Fab"))
    (fp_line (start -0.45 -1.3) (end 0.9 -1.3)
      (stroke (width 0.15) (type solid)) (layer "F.Fab"))
    (fp_line (start 0.9 -1.3) (end 0.9 1.3)
      (stroke (width 0.15) (type solid)) (layer "F.Fab"))
    (fp_line (start 0.9 1.3) (end -0.9 1.3)
      (stroke (width 0.15) (type solid)) (layer "F.Fab"))
    (pad "1" smd roundrect (at -1 -0.75 270) (size 0.8 0.3) (layers "F.Cu" "F.Paste" "F.Mask") (roundrect_rratio 0.25)
      (net 1 "GND") (pinfunction "GND") (pintype "power_in") (zone_connect 2))
    (pad "2" smd roundrect (at -1 -0.25 270) (size 0.8 0.3) (layers "F.Cu" "F.Paste" "F.Mask") (roundrect_rratio 0.25)
      (net 686 "Net-(U48-EN)") (pinfunction "EN") (pintype "input") (zone_connect 2))
    (pad "3" smd roundrect (at -1 0.248 270) (size 0.8 0.3) (layers "F.Cu" "F.Paste" "F.Mask") (roundrect_rratio 0.25)
      (net 255 "Net-(U48-FB)") (pinfunction "FB") (pintype "input") (zone_connect 2))
    (pad "4" smd roundrect (at -1 0.748 270) (size 0.8 0.3) (layers "F.Cu" "F.Paste" "F.Mask") (roundrect_rratio 0.25)
      (net 782 "unconnected-(U48-NC-Pad4)") (pinfunction "NC") (pintype "no_connect") (zone_connect 2))
    (pad "5" smd roundrect (at -0.25 0.998 180) (size 1.8 0.3) (layers "F.Cu" "F.Paste" "F.Mask") (roundrect_rratio 0.25)
      (net 251 "Net-(U48-SS)") (pinfunction "SS") (pintype "input") (zone_connect 2))
    (pad "6" smd roundrect (at 0.248 0.998 180) (size 1.8 0.3) (layers "F.Cu" "F.Paste" "F.Mask") (roundrect_rratio 0.25)
      (net 249 "Net-(U48-PVCC)") (pinfunction "PVCC") (pintype "output") (zone_connect 2))
    (pad "7" smd roundrect (at 0.998 0.748 270) (size 0.8 0.3) (layers "F.Cu" "F.Paste" "F.Mask") (roundrect_rratio 0.25)
      (net 783 "unconnected-(U48-NC-Pad7)") (pinfunction "NC") (pintype "no_connect") (zone_connect 2))
    (pad "8" smd roundrect (at 0.998 0.248 270) (size 0.8 0.3) (layers "F.Cu" "F.Paste" "F.Mask") (roundrect_rratio 0.25)
      (net 784 "unconnected-(U48-PG-Pad8)") (pinfunction "PG") (pintype "output+no_connect") (zone_connect 2))
    (pad "9" smd roundrect (at 0.998 -0.25 270) (size 0.8 0.3) (layers "F.Cu" "F.Paste" "F.Mask") (roundrect_rratio 0.25)
      (net 14 "/Power Supply/DC/DC conventers/DC_MAIN_BUS") (pinfunction "VIN") (pintype "passive") (zone_connect 2))
    (pad "10" smd roundrect (at 0.998 -0.75 270) (size 0.8 0.3) (layers "F.Cu" "F.Paste" "F.Mask") (roundrect_rratio 0.25)
      (net 14 "/Power Supply/DC/DC conventers/DC_MAIN_BUS") (pinfunction "VIN") (pintype "power_in") (zone_connect 2))
    (pad "11" smd roundrect (at 0.583 -1.476 180) (size 0.85 0.3) (layers "F.Cu" "F.Paste" "F.Mask") (roundrect_rratio 0.25)
      (net 253 "Net-(U48-BOOT)") (pinfunction "BOOT") (pintype "output") (zone_connect 2))
    (pad "12" smd roundrect (at -0.003 -1.2) (size 1.4 0.47) (layers "F.Cu" "F.Paste" "F.Mask") (roundrect_rratio 0.25)
      (net 366 "/Power Supply/DC/DC conventers/SW_SOM_5V") (pinfunction "SW") (pintype "power_out") (zone_connect 2))
    (pad "13" smd roundrect (at -0.585 -1.476 180) (size 0.85 0.3) (layers "F.Cu" "F.Paste" "F.Mask") (roundrect_rratio 0.25)
      (net 1 "GND") (pinfunction "GND") (pintype "passive") (zone_connect 2))
  )
	(footprint "kria-k26-devboard-footprints:C_0402_1005Metric" (layer "F.Cu")
    (at 176.275 125.975)
    (descr "Capacitor SMD 0402")
    (tags "capacitor SMD 0402")
    (property "Author" "Antmicro")
    (property "Dielectric" "")
    (property "License" "Apache-2.0")
    (property "MPN" "GRM155R71H392KA01D")
    (property "Manufacturer" "Murata")
    (property "Sheetfile" "dc-dc-conventers.kicad_sch")
    (property "Sheetname" "DC/DC conventers")
    (property "Val" "3n9")
    (property "Voltage" "")
    (property "ki_description" " ")
    (attr smd)
    (fp_text reference "C190" (at -1.255 3.135) (layer "F.SilkS")
        (effects (font (size 0.7 0.7) (thickness 0.15)) (justify left bottom))
    )
    (fp_text value "C_3n9_0402" (at 0 1.4) (layer "F.Fab") hide
        (effects (font (size 0.7 0.7) (thickness 0.15)) (justify left bottom))
    )
    (fp_text user "${REFERENCE}" (at -0.932 3.168) (layer "F.Fab") hide
        (effects (font (size 0.7 0.7) (thickness 0.15)) (justify left bottom))
    )
    (fp_text user "License: Apache-2.0" (at -0.932 5.17) (layer "F.Fab") hide
        (effects (font (size 0.7 0.7) (thickness 0.15)) (justify left bottom))
    )
    (fp_text user "Author: Antmicro" (at -0.932 4.17) (layer "F.Fab") hide
        (effects (font (size 0.7 0.7) (thickness 0.15)) (justify left bottom))
    )
    (fp_rect (start -0.94 -0.47) (end 0.94 0.47)
      (stroke (width 0.05) (type solid)) (fill none) (layer "F.CrtYd"))
    (fp_rect (start -0.499 -0.249) (end 0.499 0.249)
      (stroke (width 0.15) (type solid)) (fill none) (layer "F.Fab"))
    (pad "1" smd roundrect (at -0.484 0) (size 0.59 0.64) (layers "F.Cu" "F.Paste" "F.Mask") (roundrect_rratio 0.25)
      (net 251 "Net-(U48-SS)") (pintype "passive"))
    (pad "2" smd roundrect (at 0.484 0) (size 0.59 0.64) (layers "F.Cu" "F.Paste" "F.Mask") (roundrect_rratio 0.25)
      (net 1 "GND") (pintype "passive"))
  )
	(footprint "kria-k26-devboard-footprints:LED_0603_1608Metric_G" (layer "F.Cu")
    (at 179.25 127.95)
    (descr "LED SMD 0603 Green")
    (tags "LED SMD 0603 Green")
    (property "Author" "Antmicro")
    (property "Color" "Green")
    (property "License" "Apache-2.0")
    (property "MPN" "LG L29K-G2J1-24-Z")
    (property "Manufacturer" "OSRAM")
    (property "Sheetfile" "dc-dc-conventers.kicad_sch")
    (property "Sheetname" "DC/DC conventers")
    (property "ki_description" "LED, Green, SMT, 0603, 20 mA, 2.1 V, 570 nm")
    (property "ki_keywords" "0603, SMT, DIODE, SEMICONDUCTOR, UNICOLOR")
    (attr smd)
    (fp_text reference "D12" (at -1.53 1.27) (layer "F.SilkS")
        (effects (font (size 0.7 0.7) (thickness 0.15)) (justify left bottom))
    )
    (fp_text value "LED_G_0603_LG_L29K-G2J1-24-Z" (at 0 1.6) (layer "F.Fab") hide
        (effects (font (size 0.7 0.7) (thickness 0.15)) (justify left bottom))
    )
    (fp_text user "Author: Antmicro" (at -1.31 4.769) (layer "F.Fab") hide
        (effects (font (size 0.7 0.7) (thickness 0.15)) (justify left bottom))
    )
    (fp_text user "License: Apache-2.0" (at -1.31 5.769) (layer "F.Fab") hide
        (effects (font (size 0.7 0.7) (thickness 0.15)) (justify left bottom))
    )
    (fp_text user "${REFERENCE}" (at -1.31 3.769) (layer "F.Fab") hide
        (effects (font (size 0.7 0.7) (thickness 0.15)) (justify left bottom))
    )
    (fp_line (start -0.27 -0.35) (end 0.27 -0.35)
      (stroke (width 0.15) (type solid)) (layer "F.SilkS"))
    (fp_line (start -0.27 0.351) (end 0.27 0.351)
      (stroke (width 0.15) (type solid)) (layer "F.SilkS"))
    (fp_line (start -0.106328 -0.200008) (end -0.106328 0.199992)
      (stroke (width 0.1) (type solid)) (layer "F.SilkS"))
    (fp_line (start -0.106328 -0.200008) (end 0.093672 -0.000008)
      (stroke (width 0.1) (type solid)) (layer "F.SilkS"))
    (fp_line (start -0.106328 -0.000008) (end -0.29 0)
      (stroke (width 0.1) (type solid)) (layer "F.SilkS"))
    (fp_line (start 0.093672 -0.200008) (end 0.093672 0.199992)
      (stroke (width 0.1) (type solid)) (layer "F.SilkS"))
    (fp_line (start 0.093672 -0.000008) (end -0.106328 0.199992)
      (stroke (width 0.1) (type solid)) (layer "F.SilkS"))
    (fp_line (start 0.093672 -0.000008) (end 0.293672 -0.000008)
      (stroke (width 0.1) (type solid)) (layer "F.SilkS"))
    (fp_line (start 1.25 0.32) (end 1.25 -0.32)
      (stroke (width 0.15) (type solid)) (layer "F.SilkS"))
    (fp_rect (start 1.26 0.65) (end -1.26 -0.65)
      (stroke (width 0.05) (type solid)) (fill none) (layer "F.CrtYd"))
    (fp_line (start -0.599 0) (end -0.201 0)
      (stroke (width 0.15) (type solid)) (layer "F.Fab"))
    (fp_line (start -0.201 -0.2) (end -0.201 0)
      (stroke (width 0.15) (type solid)) (layer "F.Fab"))
    (fp_line (start -0.201 0) (end -0.201 0.202)
      (stroke (width 0.15) (type solid)) (layer "F.Fab"))
    (fp_line (start -0.201 0.202) (end 0.101 0)
      (stroke (width 0.15) (type solid)) (layer "F.Fab"))
    (fp_line (start 0.101 0) (end -0.201 -0.2)
      (stroke (width 0.15) (type solid)) (layer "F.Fab"))
    (fp_line (start 0.199 -0.2) (end 0.199 -0.1)
      (stroke (width 0.15) (type solid)) (layer "F.Fab"))
    (fp_line (start 0.199 0) (end 0.597 0)
      (stroke (width 0.15) (type solid)) (layer "F.Fab"))
    (fp_line (start 0.199 0.202) (end 0.199 -0.1)
      (stroke (width 0.15) (type solid)) (layer "F.Fab"))
    (fp_rect (start -0.848 -0.4) (end 0.85 0.402)
      (stroke (width 0.15) (type solid)) (fill none) (layer "F.Fab"))
    (pad "1" smd rect (at -0.75 0 180) (size 0.8 0.8) (layers "F.Cu" "F.Paste" "F.Mask")
      (net 329 "Net-(D12-Pad1)") (pintype "passive"))
    (pad "2" smd rect (at 0.75 0 180) (size 0.8 0.8) (layers "F.Cu" "F.Paste" "F.Mask")
      (net 1 "GND") (pinfunction "2") (pintype "passive"))
  )
)
